(kicad_pcb
	(version 20260206)
	(generator "pcbnew")
	(generator_version "10.0")
	(general
		(thickness 1.6)
		(legacy_teardrops no)
	)
	(paper "A4")
	(title_block
		(title "01162023_DA0F0TEBIF0_F0T_Expander_BD_F_brd_V02_OCP.brd")
		(comment 1 "Grand Teton / footprints 5996-6001 of 9728")
	)
	(layers
		(0 "F.Cu" signal "TOP")
		(4 "In1.Cu" signal "GND")
		(6 "In2.Cu" signal "VCC")
		(8 "In3.Cu" signal "VCC1")
		(10 "In4.Cu" signal "GND1")
		(12 "In5.Cu" signal "IN1")
		(14 "In6.Cu" signal "GND2")
		(16 "In7.Cu" signal "IN2")
		(18 "In8.Cu" signal "GND3")
		(20 "In9.Cu" signal "IN3")
		(22 "In10.Cu" signal "GND4")
		(24 "In11.Cu" signal "IN4")
		(26 "In12.Cu" signal "GND5")
		(28 "In13.Cu" signal "IN5")
		(30 "In14.Cu" signal "GND6")
		(32 "In15.Cu" signal "IN6")
		(34 "In16.Cu" signal "GND7")
		(2 "B.Cu" signal "BOTTOM")
		(9 "F.Adhes" user "F.Adhesive")
		(11 "B.Adhes" user "B.Adhesive")
		(13 "F.Paste" user "Package Geometry/Pastemask Top")
		(15 "B.Paste" user "Package Geometry/Pastemask Bottom")
		(5 "F.SilkS" user "Ref Des/Silkscreen Top")
		(7 "B.SilkS" user "Ref Des/Silkscreen Bottom")
		(1 "F.Mask" user "Board Geometry/Soldermask Top")
		(3 "B.Mask" user "Board Geometry/Soldermask Bottom")
		(17 "Dwgs.User" user "User.Drawings")
		(19 "Cmts.User" user "User.Comments")
		(21 "Eco1.User" user "User.Eco1")
		(23 "Eco2.User" user "User.Eco2")
		(25 "Edge.Cuts" user "Board Geometry/Outline")
		(27 "Margin" user)
		(31 "F.CrtYd" user "Package Geometry/Place Bound Top")
		(29 "B.CrtYd" user "Package Geometry/Place Bound Bottom")
		(35 "F.Fab" user "Ref Des/Assembly Top")
		(33 "B.Fab" user "Ref Des/Assembly Bottom")
	)
	(footprint ""
		(layer "F.Cu")
		(at 362.3691 -293.5351 90)
		(property "Reference" "PL16"
			(at -5.014468 8.645398 90)
			(unlocked yes)
			(layer "F.SilkS")
			(effects
				(font
					(size 0.7874 0.5842)
					(thickness 0.1524)
				)
				(justify left)
			)
		)
		(property "Value" ""
			(at 0 0 90)
			(layer "F.Fab")
			(effects
				(font
					(size 1.27 1.27)
				)
			)
		)
		(duplicate_pad_numbers_are_jumpers no)
		(fp_line
			(start 4.800092 -3.199892)
			(end 4.800092 -1.6764)
			(stroke
				(width 0.1524)
				(type default)
			)
			(layer "F.SilkS")
		)
		(fp_line
			(start -4.800092 -3.199892)
			(end 4.800092 -3.199892)
			(stroke
				(width 0.1524)
				(type default)
			)
			(layer "F.SilkS")
		)
		(fp_line
			(start -4.800092 -1.6764)
			(end -4.800092 -3.199892)
			(stroke
				(width 0.1524)
				(type default)
			)
			(layer "F.SilkS")
		)
		(fp_line
			(start 4.800092 1.6764)
			(end 4.800092 3.199892)
			(stroke
				(width 0.1524)
				(type default)
			)
			(layer "F.SilkS")
		)
		(fp_line
			(start 4.800092 3.199892)
			(end -4.800092 3.199892)
			(stroke
				(width 0.1524)
				(type default)
			)
			(layer "F.SilkS")
		)
		(fp_line
			(start -4.800092 3.199892)
			(end -4.800092 1.6764)
			(stroke
				(width 0.1524)
				(type default)
			)
			(layer "F.SilkS")
		)
		(fp_line
			(start 4.800092 -3.199892)
			(end 4.800092 3.199892)
			(stroke
				(width 0.1)
				(type default)
			)
			(layer "F.Fab")
		)
		(fp_line
			(start -4.800092 -3.199892)
			(end 4.800092 -3.199892)
			(stroke
				(width 0.1)
				(type default)
			)
			(layer "F.Fab")
		)
		(fp_line
			(start 4.800092 3.199892)
			(end -4.800092 3.199892)
			(stroke
				(width 0.1)
				(type default)
			)
			(layer "F.Fab")
		)
		(fp_line
			(start -4.800092 3.199892)
			(end -4.800092 -3.199892)
			(stroke
				(width 0.1)
				(type default)
			)
			(layer "F.Fab")
		)
		(pad "1" smd rect
			(at -3.074924 0 180)
			(size 3.0988 3.3528)
			(layers "F.Cu" "F.Mask" "F.Paste")
			(net "SW_P0V8_PEX3_PH2")
		)
		(pad "2" smd rect
			(at 3.074924 0 180)
			(size 3.0988 3.3528)
			(layers "F.Cu" "F.Mask" "F.Paste")
			(net "P0V8_PEX3")
		)
	)
	(footprint ""
		(layer "F.Cu")
		(at 276.979126 -402.33219 90)
		(property "Reference" "R1807"
			(at 0 0 90)
			(layer "F.SilkS")
			(hide yes)
			(effects
				(font
					(size 1.27 1.27)
				)
			)
		)
		(property "Value" ""
			(at 0 0 90)
			(layer "F.Fab")
			(effects
				(font
					(size 1.27 1.27)
				)
			)
		)
		(duplicate_pad_numbers_are_jumpers no)
		(fp_line
			(start 0.7874 -0.4064)
			(end 0.7874 0.4064)
			(stroke
				(width 0.1524)
				(type default)
			)
			(layer "F.SilkS")
		)
		(fp_line
			(start -0.7874 -0.4064)
			(end 0.7874 -0.4064)
			(stroke
				(width 0.1524)
				(type default)
			)
			(layer "F.SilkS")
		)
		(fp_line
			(start 0.7874 0.4064)
			(end -0.7874 0.4064)
			(stroke
				(width 0.1524)
				(type default)
			)
			(layer "F.SilkS")
		)
		(fp_line
			(start -0.7874 0.4064)
			(end -0.7874 -0.4064)
			(stroke
				(width 0.1524)
				(type default)
			)
			(layer "F.SilkS")
		)
		(fp_line
			(start -0.12065 -0.305054)
			(end -0.12065 -0.2794)
			(stroke
				(width 0.1)
				(type default)
			)
			(layer "F.Fab")
		)
		(fp_line
			(start -0.67945 -0.305054)
			(end -0.12065 -0.305054)
			(stroke
				(width 0.1)
				(type default)
			)
			(layer "F.Fab")
		)
		(fp_line
			(start 0.67945 -0.3048)
			(end 0.67945 0.3048)
			(stroke
				(width 0.1)
				(type default)
			)
			(layer "F.Fab")
		)
		(fp_line
			(start 0.12065 -0.3048)
			(end 0.67945 -0.3048)
			(stroke
				(width 0.1)
				(type default)
			)
			(layer "F.Fab")
		)
		(fp_line
			(start 0.12065 -0.2794)
			(end 0.12065 -0.3048)
			(stroke
				(width 0.1)
				(type default)
			)
			(layer "F.Fab")
		)
		(fp_line
			(start -0.12065 -0.2794)
			(end 0.12065 -0.2794)
			(stroke
				(width 0.1)
				(type default)
			)
			(layer "F.Fab")
		)
		(fp_line
			(start 0.120396 0.2794)
			(end -0.12065 0.2794)
			(stroke
				(width 0.1)
				(type default)
			)
			(layer "F.Fab")
		)
		(fp_line
			(start -0.12065 0.2794)
			(end -0.12065 0.3048)
			(stroke
				(width 0.1)
				(type default)
			)
			(layer "F.Fab")
		)
		(fp_line
			(start 0.67945 0.3048)
			(end 0.120396 0.3048)
			(stroke
				(width 0.1)
				(type default)
			)
			(layer "F.Fab")
		)
		(fp_line
			(start 0.120396 0.3048)
			(end 0.120396 0.2794)
			(stroke
				(width 0.1)
				(type default)
			)
			(layer "F.Fab")
		)
		(fp_line
			(start -0.12065 0.3048)
			(end -0.67945 0.3048)
			(stroke
				(width 0.1)
				(type default)
			)
			(layer "F.Fab")
		)
		(fp_line
			(start -0.67945 0.3048)
			(end -0.67945 -0.305054)
			(stroke
				(width 0.1)
				(type default)
			)
			(layer "F.Fab")
		)
		(pad "1" smd circle
			(at -0.40005 0 90)
			(size 0 0)
			(layers "F.Cu" "F.Mask" "F.Paste")
			(net "MB_BMC_MON_ISO")
		)
		(pad "2" smd circle
			(at 0.40005 0 90)
			(size 0 0)
			(layers "F.Cu" "F.Mask" "F.Paste")
			(net "MB_BMC_MON_ISO_R")
		)
	)
	(footprint ""
		(layer "F.Cu")
		(at 239.813338 -139.376404)
		(property "Reference" "R854"
			(at 0 0 0)
			(layer "F.SilkS")
			(hide yes)
			(effects
				(font
					(size 1.27 1.27)
				)
			)
		)
		(property "Value" ""
			(at 0 0 0)
			(layer "F.Fab")
			(effects
				(font
					(size 1.27 1.27)
				)
			)
		)
		(duplicate_pad_numbers_are_jumpers no)
		(fp_line
			(start -0.7874 -0.4064)
			(end 0.7874 -0.4064)
			(stroke
				(width 0.1524)
				(type default)
			)
			(layer "F.SilkS")
		)
		(fp_line
			(start -0.7874 0.4064)
			(end -0.7874 -0.4064)
			(stroke
				(width 0.1524)
				(type default)
			)
			(layer "F.SilkS")
		)
		(fp_line
			(start 0.7874 -0.4064)
			(end 0.7874 0.4064)
			(stroke
				(width 0.1524)
				(type default)
			)
			(layer "F.SilkS")
		)
		(fp_line
			(start 0.7874 0.4064)
			(end -0.7874 0.4064)
			(stroke
				(width 0.1524)
				(type default)
			)
			(layer "F.SilkS")
		)
		(fp_line
			(start -0.67945 -0.305054)
			(end -0.12065 -0.305054)
			(stroke
				(width 0.1)
				(type default)
			)
			(layer "F.Fab")
		)
		(fp_line
			(start -0.67945 0.3048)
			(end -0.67945 -0.305054)
			(stroke
				(width 0.1)
				(type default)
			)
			(layer "F.Fab")
		)
		(fp_line
			(start -0.12065 -0.305054)
			(end -0.12065 -0.2794)
			(stroke
				(width 0.1)
				(type default)
			)
			(layer "F.Fab")
		)
		(fp_line
			(start -0.12065 -0.2794)
			(end 0.12065 -0.2794)
			(stroke
				(width 0.1)
				(type default)
			)
			(layer "F.Fab")
		)
		(fp_line
			(start -0.12065 0.2794)
			(end -0.12065 0.3048)
			(stroke
				(width 0.1)
				(type default)
			)
			(layer "F.Fab")
		)
		(fp_line
			(start -0.12065 0.3048)
			(end -0.67945 0.3048)
			(stroke
				(width 0.1)
				(type default)
			)
			(layer "F.Fab")
		)
		(fp_line
			(start 0.120396 0.2794)
			(end -0.12065 0.2794)
			(stroke
				(width 0.1)
				(type default)
			)
			(layer "F.Fab")
		)
		(fp_line
			(start 0.120396 0.3048)
			(end 0.120396 0.2794)
			(stroke
				(width 0.1)
				(type default)
			)
			(layer "F.Fab")
		)
		(fp_line
			(start 0.12065 -0.3048)
			(end 0.67945 -0.3048)
			(stroke
				(width 0.1)
				(type default)
			)
			(layer "F.Fab")
		)
		(fp_line
			(start 0.12065 -0.2794)
			(end 0.12065 -0.3048)
			(stroke
				(width 0.1)
				(type default)
			)
			(layer "F.Fab")
		)
		(fp_line
			(start 0.67945 -0.3048)
			(end 0.67945 0.3048)
			(stroke
				(width 0.1)
				(type default)
			)
			(layer "F.Fab")
		)
		(fp_line
			(start 0.67945 0.3048)
			(end 0.120396 0.3048)
			(stroke
				(width 0.1)
				(type default)
			)
			(layer "F.Fab")
		)
		(pad "1" smd circle
			(at -0.40005 0)
			(size 0 0)
			(layers "F.Cu" "F.Mask" "F.Paste")
			(net "P3V3_AUX")
		)
		(pad "2" smd circle
			(at 0.40005 0)
			(size 0 0)
			(layers "F.Cu" "F.Mask" "F.Paste")
			(net "PWRGD_P12V_NIC4")
		)
	)
	(footprint ""
		(layer "F.Cu")
		(at 350.647 -162.179 90)
		(property "Reference" "C3604"
			(at 0 0 90)
			(layer "F.SilkS")
			(hide yes)
			(effects
				(font
					(size 1.27 1.27)
				)
			)
		)
		(property "Value" ""
			(at 0 0 90)
			(layer "F.Fab")
			(effects
				(font
					(size 1.27 1.27)
				)
			)
		)
		(duplicate_pad_numbers_are_jumpers no)
		(fp_line
			(start 0.7874 -0.4064)
			(end 0.7874 0.4064)
			(stroke
				(width 0.1524)
				(type default)
			)
			(layer "F.SilkS")
		)
		(fp_line
			(start -0.7874 -0.4064)
			(end 0.7874 -0.4064)
			(stroke
				(width 0.1524)
				(type default)
			)
			(layer "F.SilkS")
		)
		(fp_line
			(start 0.7874 0.4064)
			(end -0.7874 0.4064)
			(stroke
				(width 0.1524)
				(type default)
			)
			(layer "F.SilkS")
		)
		(fp_line
			(start -0.7874 0.4064)
			(end -0.7874 -0.4064)
			(stroke
				(width 0.1524)
				(type default)
			)
			(layer "F.SilkS")
		)
		(fp_line
			(start -0.12065 -0.305054)
			(end -0.12065 -0.2794)
			(stroke
				(width 0.1)
				(type default)
			)
			(layer "F.Fab")
		)
		(fp_line
			(start -0.67945 -0.305054)
			(end -0.12065 -0.305054)
			(stroke
				(width 0.1)
				(type default)
			)
			(layer "F.Fab")
		)
		(fp_line
			(start 0.67945 -0.3048)
			(end 0.67945 0.3048)
			(stroke
				(width 0.1)
				(type default)
			)
			(layer "F.Fab")
		)
		(fp_line
			(start 0.12065 -0.3048)
			(end 0.67945 -0.3048)
			(stroke
				(width 0.1)
				(type default)
			)
			(layer "F.Fab")
		)
		(fp_line
			(start 0.12065 -0.2794)
			(end 0.12065 -0.3048)
			(stroke
				(width 0.1)
				(type default)
			)
			(layer "F.Fab")
		)
		(fp_line
			(start -0.12065 -0.2794)
			(end 0.12065 -0.2794)
			(stroke
				(width 0.1)
				(type default)
			)
			(layer "F.Fab")
		)
		(fp_line
			(start 0.120396 0.2794)
			(end -0.12065 0.2794)
			(stroke
				(width 0.1)
				(type default)
			)
			(layer "F.Fab")
		)
		(fp_line
			(start -0.12065 0.2794)
			(end -0.12065 0.3048)
			(stroke
				(width 0.1)
				(type default)
			)
			(layer "F.Fab")
		)
		(fp_line
			(start 0.67945 0.3048)
			(end 0.120396 0.3048)
			(stroke
				(width 0.1)
				(type default)
			)
			(layer "F.Fab")
		)
		(fp_line
			(start 0.120396 0.3048)
			(end 0.120396 0.2794)
			(stroke
				(width 0.1)
				(type default)
			)
			(layer "F.Fab")
		)
		(fp_line
			(start -0.12065 0.3048)
			(end -0.67945 0.3048)
			(stroke
				(width 0.1)
				(type default)
			)
			(layer "F.Fab")
		)
		(fp_line
			(start -0.67945 0.3048)
			(end -0.67945 -0.305054)
			(stroke
				(width 0.1)
				(type default)
			)
			(layer "F.Fab")
		)
		(pad "1" smd circle
			(at -0.40005 0 90)
			(size 0 0)
			(layers "F.Cu" "F.Mask" "F.Paste")
			(net "P3V3_AUX")
		)
		(pad "2" smd circle
			(at 0.40005 0 90)
			(size 0 0)
			(layers "F.Cu" "F.Mask" "F.Paste")
			(net "GND")
		)
	)
	(footprint ""
		(layer "F.Cu")
		(at 297.009566 -441.70346)
		(property "Reference" "X72"
			(at -0.1778 -1.92913 0)
			(unlocked yes)
			(layer "F.SilkS")
			(effects
				(font
					(size 0.7874 0.5842)
					(thickness 0.1524)
				)
				(justify left)
			)
		)
		(property "Value" ""
			(at 0 0 0)
			(layer "F.Fab")
			(effects
				(font
					(size 1.27 1.27)
				)
			)
		)
		(property "Device Type" "TP_TDR_4P_FTS_MPKT4_H025P0200_IO_TP15_TP_TDR_4P_DIP"
			(at 1.30175 1.27 90)
			(unlocked yes)
			(layer "F.Fab")
			(hide yes)
			(effects
				(font
					(size 0.635 0.4064)
					(thickness 0.1524)
				)
			)
		)
		(property "User Part Number" "TP15"
			(at 1.30175 1.27 90)
			(unlocked yes)
			(layer "Cmts.User")
			(hide yes)
			(effects
				(font
					(size 0.635 0.4064)
					(thickness 0.1524)
				)
			)
		)
		(duplicate_pad_numbers_are_jumpers no)
		(fp_line
			(start 0 -1.27)
			(end 0 -0.635)
			(stroke
				(width 0.1524)
				(type default)
			)
			(layer "F.SilkS")
		)
		(fp_line
			(start 0 0.635)
			(end 0 1.905)
			(stroke
				(width 0.1524)
				(type default)
			)
			(layer "F.SilkS")
		)
		(fp_line
			(start 0 3.175)
			(end 0 3.81)
			(stroke
				(width 0.1524)
				(type default)
			)
			(layer "F.SilkS")
		)
		(fp_line
			(start 0 3.81)
			(end 2.54 3.81)
			(stroke
				(width 0.1524)
				(type default)
			)
			(layer "F.SilkS")
		)
		(fp_line
			(start 2.54 -1.27)
			(end 0 -1.27)
			(stroke
				(width 0.1524)
				(type default)
			)
			(layer "F.SilkS")
		)
		(fp_line
			(start 2.54 -1.1303)
			(end 2.54 -1.27)
			(stroke
				(width 0.1524)
				(type default)
			)
			(layer "F.SilkS")
		)
		(fp_line
			(start 2.54 1.4097)
			(end 2.54 1.1303)
			(stroke
				(width 0.1524)
				(type default)
			)
			(layer "F.SilkS")
		)
		(fp_line
			(start 2.54 3.81)
			(end 2.54 3.6703)
			(stroke
				(width 0.1524)
				(type default)
			)
			(layer "F.SilkS")
		)
		(fp_poly
			(pts
				(xy -0.761746 0) (xy -2.285746 -0.762) (xy -2.285746 0.762)
			)
			(stroke
				(width 0)
				(type default)
			)
			(fill yes)
			(layer "F.SilkS")
		)
		(fp_line
			(start 0 -1.27)
			(end 0 3.81)
			(stroke
				(width 0.1)
				(type default)
			)
			(layer "F.Fab")
		)
		(fp_line
			(start 0 3.81)
			(end 2.54 3.81)
			(stroke
				(width 0.1)
				(type default)
			)
			(layer "F.Fab")
		)
		(fp_line
			(start 2.54 -1.27)
			(end 0 -1.27)
			(stroke
				(width 0.1)
				(type default)
			)
			(layer "F.Fab")
		)
		(fp_line
			(start 2.54 3.81)
			(end 2.54 -1.27)
			(stroke
				(width 0.1)
				(type default)
			)
			(layer "F.Fab")
		)
		(fp_poly
			(pts
				(xy -0.761746 0) (xy -2.285746 -0.762) (xy -2.285746 0.762)
			)
			(stroke
				(width 0)
				(type default)
			)
			(fill yes)
			(layer "F.Fab")
		)
		(pad "1" thru_hole circle
			(at 0 0)
			(size 1.0033 1.0033)
			(drill 0.249936)
			(layers "*.Cu" "*.Mask")
			(remove_unused_layers no)
			(net "TDR_DIFF_100_IN3_DIP")
			(clearance 0.10795)
			(thermal_gap 0.10795)
			(padstack
				(mode front_inner_back)
				(layer "Inner"
					(shape circle)
					(size 0.8001 0.8001)
					(clearance 0.1524)
				)
				(layer "B.Cu"
					(shape circle)
					(size 1.0033 1.0033)
					(clearance 0.10795)
				)
			)
		)
		(pad "2" thru_hole circle
			(at 2.54 0)
			(size 1.9939 1.9939)
			(drill 0.249936)
			(layers "*.Cu" "*.Mask")
			(remove_unused_layers no)
			(net "COUPON_GND1")
			(clearance 0.10795)
			(thermal_gap 0.10795)
			(padstack
				(mode front_inner_back)
				(layer "Inner"
					(shape circle)
					(size 0.8001 0.8001)
					(clearance 0.1524)
				)
				(layer "B.Cu"
					(shape circle)
					(size 1.9939 1.9939)
					(clearance 0.10795)
				)
			)
		)
		(pad "3" thru_hole circle
			(at 2.54 2.54)
			(size 1.9939 1.9939)
			(drill 0.249936)
			(layers "*.Cu" "*.Mask")
			(remove_unused_layers no)
			(net "COUPON_GND1")
			(clearance 0.10795)
			(thermal_gap 0.10795)
			(padstack
				(mode front_inner_back)
				(layer "Inner"
					(shape circle)
					(size 0.8001 0.8001)
					(clearance 0.1524)
				)
				(layer "B.Cu"
					(shape circle)
					(size 1.9939 1.9939)
					(clearance 0.10795)
				)
			)
		)
		(pad "4" thru_hole circle
			(at 0 2.54)
			(size 1.0033 1.0033)
			(drill 0.249936)
			(layers "*.Cu" "*.Mask")
			(remove_unused_layers no)
			(net "TDR_DIFF_100_IN3_DIN")
			(clearance 0.10795)
			(thermal_gap 0.10795)
			(padstack
				(mode front_inner_back)
				(layer "Inner"
					(shape circle)
					(size 0.8001 0.8001)
					(clearance 0.1524)
				)
				(layer "B.Cu"
					(shape circle)
					(size 1.0033 1.0033)
					(clearance 0.10795)
				)
			)
		)
	)
	(footprint ""
		(layer "F.Cu")
		(at 115.356386 -83.38439 180)
		(property "Reference" "R1143"
			(at 0 0 180)
			(layer "F.SilkS")
			(hide yes)
			(effects
				(font
					(size 1.27 1.27)
				)
			)
		)
		(property "Value" ""
			(at 0 0 180)
			(layer "F.Fab")
			(effects
				(font
					(size 1.27 1.27)
				)
			)
		)
		(duplicate_pad_numbers_are_jumpers no)
		(fp_line
			(start 0.7874 0.4064)
			(end -0.7874 0.4064)
			(stroke
				(width 0.1524)
				(type default)
			)
			(layer "F.SilkS")
		)
		(fp_line
			(start 0.67945 0.3048)
			(end 0.120396 0.3048)
			(stroke
				(width 0.1)
				(type default)
			)
			(layer "F.Fab")
		)
		(fp_line
			(start 0.67945 -0.3048)
			(end 0.67945 0.3048)
			(stroke
				(width 0.1)
				(type default)
			)
			(layer "F.Fab")
		)
		(fp_line
			(start 0.12065 -0.2794)
			(end 0.12065 -0.3048)
			(stroke
				(width 0.1)
				(type default)
			)
			(layer "F.Fab")
		)
		(fp_line
			(start 0.12065 -0.3048)
			(end 0.67945 -0.3048)
			(stroke
				(width 0.1)
				(type default)
			)
			(layer "F.Fab")
		)
		(fp_line
			(start 0.120396 0.3048)
			(end 0.120396 0.2794)
			(stroke
				(width 0.1)
				(type default)
			)
			(layer "F.Fab")
		)
		(fp_line
			(start 0.120396 0.2794)
			(end -0.12065 0.2794)
			(stroke
				(width 0.1)
				(type default)
			)
			(layer "F.Fab")
		)
		(fp_line
			(start -0.12065 0.3048)
			(end -0.67945 0.3048)
			(stroke
				(width 0.1)
				(type default)
			)
			(layer "F.Fab")
		)
		(fp_line
			(start -0.12065 0.2794)
			(end -0.12065 0.3048)
			(stroke
				(width 0.1)
				(type default)
			)
			(layer "F.Fab")
		)
		(fp_line
			(start -0.12065 -0.2794)
			(end 0.12065 -0.2794)
			(stroke
				(width 0.1)
				(type default)
			)
			(layer "F.Fab")
		)
		(fp_line
			(start -0.12065 -0.305054)
			(end -0.12065 -0.2794)
			(stroke
				(width 0.1)
				(type default)
			)
			(layer "F.Fab")
		)
		(fp_line
			(start -0.67945 0.3048)
			(end -0.67945 -0.305054)
			(stroke
				(width 0.1)
				(type default)
			)
			(layer "F.Fab")
		)
		(fp_line
			(start -0.67945 -0.305054)
			(end -0.12065 -0.305054)
			(stroke
				(width 0.1)
				(type default)
			)
			(layer "F.Fab")
		)
		(pad "1" smd circle
			(at -0.40005 0 180)
			(size 0 0)
			(layers "F.Cu" "F.Mask" "F.Paste")
			(net "CLK_100M_DB800ZL_SSD3_R_DN")
		)
		(pad "2" smd circle
			(at 0.40005 0 180)
			(size 0 0)
			(layers "F.Cu" "F.Mask" "F.Paste")
			(net "CLK_100M_DB800ZL_SSD3_DN")
		)
	)
)
